(kicad_pcb
	(version 20260206)
	(generator "pcbnew")
	(generator_version "10.0")
	(general
		(thickness 1.6)
		(legacy_teardrops no)
	)
	(paper "A4")
	(title_block
		(title "baseboard — 13948-1b.1110WZS1818.brd")
		(comment 1 "Honey Badger (Wiwynn) / footprints 2230-2237 of 2523")
	)
	(layers
		(0 "F.Cu" signal "TOP")
		(4 "In1.Cu" signal "L2GND")
		(6 "In2.Cu" signal "L3")
		(8 "In3.Cu" signal "L4VCC")
		(10 "In4.Cu" signal "L5VCC")
		(12 "In5.Cu" signal "L6")
		(14 "In6.Cu" signal "L7GND")
		(2 "B.Cu" signal "BOTTOM")
		(9 "F.Adhes" user "F.Adhesive")
		(11 "B.Adhes" user "B.Adhesive")
		(13 "F.Paste" user "Package Geometry/Pastemask Top")
		(15 "B.Paste" user "Package Geometry/Pastemask Bottom")
		(5 "F.SilkS" user "Ref Des/Silkscreen Top")
		(7 "B.SilkS" user "Ref Des/Silkscreen Bottom")
		(1 "F.Mask" user "Board Geometry/Soldermask Top")
		(3 "B.Mask" user "Board Geometry/Soldermask Bottom")
		(17 "Dwgs.User" user "User.Drawings")
		(19 "Cmts.User" user "User.Comments")
		(21 "Eco1.User" user "User.Eco1")
		(23 "Eco2.User" user "User.Eco2")
		(25 "Edge.Cuts" user "Board Geometry/Outline")
		(27 "Margin" user)
		(31 "F.CrtYd" user "Package Geometry/Place Bound Top")
		(29 "B.CrtYd" user "Package Geometry/Place Bound Bottom")
		(35 "F.Fab" user "Ref Des/Assembly Top")
		(33 "B.Fab" user "Ref Des/Assembly Bottom")
	)
	(footprint ""
		(layer "B.Cu")
		(at 165.354 -111.379)
		(property "Reference" "Q14"
			(at 0 0 0)
			(layer "B.SilkS")
			(hide yes)
			(effects
				(font
					(size 1.27 1.27)
				)
				(justify mirror)
			)
		)
		(property "Value" "2N7002A-7-GP"
			(at -0.127 -8.9662 0)
			(unlocked yes)
			(layer "B.Fab")
			(hide yes)
			(effects
				(font
					(size 1.016 1.016)
					(thickness 0.1524)
				)
				(justify mirror)
			)
		)
		(property "Device Type" "SOT23DGS2D4H48"
			(at -0.127 -10.4902 0)
			(unlocked yes)
			(layer "B.Fab")
			(hide yes)
			(effects
				(font
					(size 1.016 1.016)
					(thickness 0.1524)
				)
				(justify mirror)
			)
		)
		(duplicate_pad_numbers_are_jumpers no)
		(fp_line
			(start -1.651 -1.778)
			(end 1.651 -1.778)
			(stroke
				(width 0.1524)
				(type default)
			)
			(layer "B.SilkS")
		)
		(fp_line
			(start -1.651 1.778)
			(end -1.651 -1.778)
			(stroke
				(width 0.1524)
				(type default)
			)
			(layer "B.SilkS")
		)
		(fp_line
			(start 1.651 -1.778)
			(end 1.651 1.778)
			(stroke
				(width 0.1524)
				(type default)
			)
			(layer "B.SilkS")
		)
		(fp_line
			(start 1.651 1.778)
			(end -1.651 1.778)
			(stroke
				(width 0.1524)
				(type default)
			)
			(layer "B.SilkS")
		)
		(fp_poly
			(pts
				(xy 1.778 1.8796) (xy 1.778 -1.8796) (xy -1.778 -1.8796) (xy -1.778 1.8796)
			)
			(stroke
				(width 0)
				(type default)
			)
			(fill no)
			(layer "B.CrtYd")
		)
		(fp_poly
			(pts
				(xy 1.778 1.8796) (xy 1.778 -1.8796) (xy -1.778 -1.8796) (xy -1.778 1.8796)
			)
			(stroke
				(width 0)
				(type default)
			)
			(fill no)
			(layer "B.Fab")
		)
		(pad "D" smd custom
			(at 0 -0.9525 180)
			(size 0.1905 0.1905)
			(layers "B.Cu" "B.Mask" "B.Paste")
			(net "P3V3_STBY_R4")
			(options
				(clearance outline)
				(anchor circle)
			)
			(primitives
				(gr_poly
					(pts
						(arc
							(start -0.1778 -0.5715)
							(mid -0.321484 -0.511984)
							(end -0.381 -0.3683)
						)
						(arc
							(start -0.381 0.3683)
							(mid -0.321484 0.511984)
							(end -0.1778 0.5715)
						)
						(arc
							(start 0.1778 0.5715)
							(mid 0.321484 0.511984)
							(end 0.381 0.3683)
						)
						(arc
							(start 0.381 -0.3683)
							(mid 0.321484 -0.511984)
							(end 0.1778 -0.5715)
						)
					)
					(width 0)
					(fill yes)
				)
			)
		)
		(pad "G" smd custom
			(at 0.98425 0.9525 180)
			(size 0.1905 0.1905)
			(layers "B.Cu" "B.Mask" "B.Paste")
			(net "P0V9_E_PG")
			(options
				(clearance outline)
				(anchor circle)
			)
			(primitives
				(gr_poly
					(pts
						(arc
							(start -0.1778 -0.5715)
							(mid -0.321484 -0.511984)
							(end -0.381 -0.3683)
						)
						(arc
							(start -0.381 0.3683)
							(mid -0.321484 0.511984)
							(end -0.1778 0.5715)
						)
						(arc
							(start 0.1778 0.5715)
							(mid 0.321484 0.511984)
							(end 0.381 0.3683)
						)
						(arc
							(start 0.381 -0.3683)
							(mid 0.321484 -0.511984)
							(end 0.1778 -0.5715)
						)
					)
					(width 0)
					(fill yes)
				)
			)
		)
		(pad "S" smd custom
			(at -0.98425 0.9525 180)
			(size 0.1905 0.1905)
			(layers "B.Cu" "B.Mask" "B.Paste")
			(net "GND")
			(options
				(clearance outline)
				(anchor circle)
			)
			(primitives
				(gr_poly
					(pts
						(arc
							(start -0.1778 -0.5715)
							(mid -0.321484 -0.511984)
							(end -0.381 -0.3683)
						)
						(arc
							(start -0.381 0.3683)
							(mid -0.321484 0.511984)
							(end -0.1778 0.5715)
						)
						(arc
							(start 0.1778 0.5715)
							(mid 0.321484 0.511984)
							(end 0.381 0.3683)
						)
						(arc
							(start 0.381 -0.3683)
							(mid 0.321484 -0.511984)
							(end 0.1778 -0.5715)
						)
					)
					(width 0)
					(fill yes)
				)
			)
		)
	)
	(footprint ""
		(layer "B.Cu")
		(at 109.99216 -33.655)
		(property "Reference" "STP26"
			(at 0 0 0)
			(layer "B.SilkS")
			(hide yes)
			(effects
				(font
					(size 1.27 1.27)
				)
				(justify mirror)
			)
		)
		(property "Value" "TPAD28"
			(at -0.0127 -1.8034 0)
			(unlocked yes)
			(layer "B.Fab")
			(hide yes)
			(effects
				(font
					(size 1.016 1.016)
					(thickness 0.1524)
				)
				(justify mirror)
			)
		)
		(property "Device Type" "TPAD28"
			(at -0.0127 -3.3274 0)
			(unlocked yes)
			(layer "B.Fab")
			(hide yes)
			(effects
				(font
					(size 1.016 1.016)
					(thickness 0.1524)
				)
				(justify mirror)
			)
		)
		(duplicate_pad_numbers_are_jumpers no)
		(fp_poly
			(pts
				(arc
					(start 0.3556 0)
					(mid -0.3556 0)
					(end 0.3556 0)
				)
			)
			(stroke
				(width 0)
				(type default)
			)
			(fill no)
			(layer "B.CrtYd")
		)
		(fp_poly
			(pts
				(arc
					(start 0.6096 0)
					(mid -0.6096 0)
					(end 0.6096 0)
				)
			)
			(stroke
				(width 0)
				(type default)
			)
			(fill no)
			(layer "B.Fab")
		)
		(pad "1" smd circle
			(at 0 0 180)
			(size 0.7112 0.7112)
			(layers "B.Cu" "B.Mask" "B.Paste")
			(net "IOC_UART_1_RX")
		)
	)
	(footprint ""
		(layer "B.Cu")
		(at 114.94897 -80.391)
		(property "Reference" "STP107"
			(at 0 0 0)
			(layer "B.SilkS")
			(hide yes)
			(effects
				(font
					(size 1.27 1.27)
				)
				(justify mirror)
			)
		)
		(property "Value" "TPAD28"
			(at -0.0127 -1.8034 0)
			(unlocked yes)
			(layer "B.Fab")
			(hide yes)
			(effects
				(font
					(size 1.016 1.016)
					(thickness 0.1524)
				)
				(justify mirror)
			)
		)
		(property "Device Type" "TPAD28"
			(at -0.0127 -3.3274 0)
			(unlocked yes)
			(layer "B.Fab")
			(hide yes)
			(effects
				(font
					(size 1.016 1.016)
					(thickness 0.1524)
				)
				(justify mirror)
			)
		)
		(duplicate_pad_numbers_are_jumpers no)
		(fp_poly
			(pts
				(arc
					(start 0.3556 0)
					(mid -0.3556 0)
					(end 0.3556 0)
				)
			)
			(stroke
				(width 0)
				(type default)
			)
			(fill no)
			(layer "B.CrtYd")
		)
		(fp_poly
			(pts
				(arc
					(start 0.6096 0)
					(mid -0.6096 0)
					(end 0.6096 0)
				)
			)
			(stroke
				(width 0)
				(type default)
			)
			(fill no)
			(layer "B.Fab")
		)
		(pad "1" smd circle
			(at 0 0 180)
			(size 0.7112 0.7112)
			(layers "B.Cu" "B.Mask" "B.Paste")
			(net "TEST_MUX_40")
		)
	)
	(footprint ""
		(layer "B.Cu")
		(at 96.774 -3.429)
		(property "Reference" "PC195"
			(at 0 0 0)
			(layer "B.SilkS")
			(hide yes)
			(effects
				(font
					(size 1.27 1.27)
				)
				(justify mirror)
			)
		)
		(property "Value" "SCD1U50V3KX-GP"
			(at 0 -2.8194 0)
			(unlocked yes)
			(layer "B.Fab")
			(hide yes)
			(effects
				(font
					(size 1.016 1.016)
					(thickness 0.1524)
				)
				(justify mirror)
			)
		)
		(property "Device Type" "C603H36"
			(at 0 -4.3434 0)
			(unlocked yes)
			(layer "B.Fab")
			(hide yes)
			(effects
				(font
					(size 1.016 1.016)
					(thickness 0.1524)
				)
				(justify mirror)
			)
		)
		(duplicate_pad_numbers_are_jumpers no)
		(fp_line
			(start -0.508 0)
			(end 0.508 0)
			(stroke
				(width 0.2032)
				(type default)
			)
			(layer "B.SilkS")
		)
		(fp_rect
			(start 0.5842 1.3335)
			(end -0.5842 -1.3335)
			(stroke
				(width 0)
				(type default)
			)
			(fill no)
			(layer "B.CrtYd")
		)
		(fp_rect
			(start 0.5842 1.3335)
			(end -0.5842 -1.3335)
			(stroke
				(width 0)
				(type default)
			)
			(fill no)
			(layer "B.Fab")
		)
		(pad "1" smd custom
			(at 0 -0.762 180)
			(size 0.2159 0.2159)
			(layers "B.Cu" "B.Mask" "B.Paste")
			(net "P0V955_C")
			(options
				(clearance outline)
				(anchor circle)
			)
			(primitives
				(gr_poly
					(pts
						(arc
							(start -0.3302 0.4318)
							(mid -0.402042 0.402042)
							(end -0.4318 0.3302)
						)
						(arc
							(start -0.4318 -0.3302)
							(mid -0.402042 -0.402042)
							(end -0.3302 -0.4318)
						)
						(arc
							(start 0.3302 -0.4318)
							(mid 0.402042 -0.402042)
							(end 0.4318 -0.3302)
						)
						(arc
							(start 0.4318 0.3302)
							(mid 0.402042 0.402042)
							(end 0.3302 0.4318)
						)
					)
					(width 0)
					(fill yes)
				)
			)
		)
		(pad "2" smd custom
			(at 0 0.762 180)
			(size 0.2159 0.2159)
			(layers "B.Cu" "B.Mask" "B.Paste")
			(net "GND")
			(options
				(clearance outline)
				(anchor circle)
			)
			(primitives
				(gr_poly
					(pts
						(arc
							(start -0.3302 0.4318)
							(mid -0.402042 0.402042)
							(end -0.4318 0.3302)
						)
						(arc
							(start -0.4318 -0.3302)
							(mid -0.402042 -0.402042)
							(end -0.3302 -0.4318)
						)
						(arc
							(start 0.3302 -0.4318)
							(mid 0.402042 -0.402042)
							(end 0.4318 -0.3302)
						)
						(arc
							(start 0.4318 0.3302)
							(mid 0.402042 0.402042)
							(end 0.3302 0.4318)
						)
					)
					(width 0)
					(fill yes)
				)
			)
		)
	)
	(footprint ""
		(layer "B.Cu")
		(at 111.26597 -81.534 180)
		(property "Reference" "SC1215"
			(at 0 0 0)
			(layer "B.SilkS")
			(hide yes)
			(effects
				(font
					(size 1.27 1.27)
				)
				(justify mirror)
			)
		)
		(property "Value" "SC1KP50V2KX-1GP"
			(at -1.1811 -2.7051 180)
			(unlocked yes)
			(layer "B.Fab")
			(hide yes)
			(effects
				(font
					(size 1.016 1.016)
					(thickness 0.1524)
				)
				(justify mirror)
			)
		)
		(property "Device Type" "C402H22"
			(at -1.1811 -4.2291 180)
			(unlocked yes)
			(layer "B.Fab")
			(hide yes)
			(effects
				(font
					(size 1.016 1.016)
					(thickness 0.1524)
				)
				(justify mirror)
			)
		)
		(duplicate_pad_numbers_are_jumpers no)
		(fp_rect
			(start 0.4318 0.9525)
			(end -0.4318 -0.9525)
			(stroke
				(width 0)
				(type default)
			)
			(fill no)
			(layer "B.CrtYd")
		)
		(fp_rect
			(start 0.4318 0.9525)
			(end -0.4318 -0.9525)
			(stroke
				(width 0)
				(type default)
			)
			(fill no)
			(layer "B.Fab")
		)
		(pad "1" smd custom
			(at 0 -0.4445)
			(size 0.1524 0.1524)
			(layers "B.Cu" "B.Mask" "B.Paste")
			(net "P1V8_E")
			(options
				(clearance outline)
				(anchor circle)
			)
			(primitives
				(gr_poly
					(pts
						(arc
							(start 0.3048 0.2032)
							(mid 0.275042 0.275042)
							(end 0.2032 0.3048)
						)
						(arc
							(start -0.2032 0.3048)
							(mid -0.275042 0.275042)
							(end -0.3048 0.2032)
						)
						(arc
							(start -0.3048 -0.2032)
							(mid -0.275042 -0.275042)
							(end -0.2032 -0.3048)
						)
						(arc
							(start 0.2032 -0.3048)
							(mid 0.275042 -0.275042)
							(end 0.3048 -0.2032)
						)
					)
					(width 0)
					(fill yes)
				)
			)
		)
		(pad "2" smd custom
			(at 0 0.4445)
			(size 0.1524 0.1524)
			(layers "B.Cu" "B.Mask" "B.Paste")
			(net "GND")
			(options
				(clearance outline)
				(anchor circle)
			)
			(primitives
				(gr_poly
					(pts
						(arc
							(start 0.3048 0.2032)
							(mid 0.275042 0.275042)
							(end 0.2032 0.3048)
						)
						(arc
							(start -0.2032 0.3048)
							(mid -0.275042 0.275042)
							(end -0.3048 0.2032)
						)
						(arc
							(start -0.3048 -0.2032)
							(mid -0.275042 -0.275042)
							(end -0.2032 -0.3048)
						)
						(arc
							(start 0.2032 -0.3048)
							(mid 0.275042 -0.275042)
							(end 0.3048 -0.2032)
						)
					)
					(width 0)
					(fill yes)
				)
			)
		)
	)
	(footprint ""
		(layer "B.Cu")
		(at 92.310966 -50.644806 -90)
		(property "Reference" "SR629"
			(at 0 0 90)
			(layer "B.SilkS")
			(hide yes)
			(effects
				(font
					(size 1.27 1.27)
				)
				(justify mirror)
			)
		)
		(property "Value" "2K2R2F-GP"
			(at -0.064008 -3.993896 270)
			(unlocked yes)
			(layer "B.Fab")
			(hide yes)
			(effects
				(font
					(size 1.016 1.016)
					(thickness 0.1524)
				)
				(justify mirror)
			)
		)
		(property "Device Type" "R402H16"
			(at -0.064008 -5.517896 270)
			(unlocked yes)
			(layer "B.Fab")
			(hide yes)
			(effects
				(font
					(size 1.016 1.016)
					(thickness 0.1524)
				)
				(justify mirror)
			)
		)
		(duplicate_pad_numbers_are_jumpers no)
		(fp_line
			(start -0.508 -0.9398)
			(end 0.508 -0.9398)
			(stroke
				(width 0.1524)
				(type default)
			)
			(layer "B.SilkS")
		)
		(fp_line
			(start 0.508 -0.9398)
			(end 0.508 0.9398)
			(stroke
				(width 0.1524)
				(type default)
			)
			(layer "B.SilkS")
		)
		(fp_rect
			(start 0.508 0.9398)
			(end -0.508 -0.9398)
			(stroke
				(width 0)
				(type default)
			)
			(fill no)
			(layer "B.CrtYd")
		)
		(fp_rect
			(start 0.508 0.9398)
			(end -0.508 -0.9398)
			(stroke
				(width 0)
				(type default)
			)
			(fill no)
			(layer "B.Fab")
		)
		(pad "1" smd custom
			(at 0 -0.4445 90)
			(size 0.1397 0.1397)
			(layers "B.Cu" "B.Mask" "B.Paste")
			(net "P1V8_C")
			(options
				(clearance outline)
				(anchor circle)
			)
			(primitives
				(gr_poly
					(pts
						(arc
							(start -0.1778 0.2794)
							(mid -0.249642 0.249642)
							(end -0.2794 0.1778)
						)
						(arc
							(start -0.2794 -0.1778)
							(mid -0.249642 -0.249642)
							(end -0.1778 -0.2794)
						)
						(arc
							(start 0.1778 -0.2794)
							(mid 0.249642 -0.249642)
							(end 0.2794 -0.1778)
						)
						(arc
							(start 0.2794 0.1778)
							(mid 0.249642 0.249642)
							(end 0.1778 0.2794)
						)
					)
					(width 0)
					(fill yes)
				)
			)
		)
		(pad "2" smd custom
			(at 0 0.4445 90)
			(size 0.1397 0.1397)
			(layers "B.Cu" "B.Mask" "B.Paste")
			(net "SIO_LOAD_0")
			(options
				(clearance outline)
				(anchor circle)
			)
			(primitives
				(gr_poly
					(pts
						(arc
							(start -0.1778 0.2794)
							(mid -0.249642 0.249642)
							(end -0.2794 0.1778)
						)
						(arc
							(start -0.2794 -0.1778)
							(mid -0.249642 -0.249642)
							(end -0.1778 -0.2794)
						)
						(arc
							(start 0.1778 -0.2794)
							(mid 0.249642 -0.249642)
							(end 0.2794 -0.1778)
						)
						(arc
							(start 0.2794 0.1778)
							(mid 0.249642 0.249642)
							(end 0.1778 0.2794)
						)
					)
					(width 0)
					(fill yes)
				)
			)
		)
	)
	(footprint ""
		(layer "B.Cu")
		(at 274.193 -184.785 90)
		(property "Reference" "R362"
			(at 0 0 90)
			(layer "B.SilkS")
			(hide yes)
			(effects
				(font
					(size 1.27 1.27)
				)
				(justify mirror)
			)
		)
		(property "Value" "3K3R2F-2-GP"
			(at -0.064008 -3.993896 90)
			(unlocked yes)
			(layer "B.Fab")
			(hide yes)
			(effects
				(font
					(size 1.016 1.016)
					(thickness 0.1524)
				)
				(justify mirror)
			)
		)
		(property "Device Type" "R402H16"
			(at -0.064008 -5.517896 90)
			(unlocked yes)
			(layer "B.Fab")
			(hide yes)
			(effects
				(font
					(size 1.016 1.016)
					(thickness 0.1524)
				)
				(justify mirror)
			)
		)
		(duplicate_pad_numbers_are_jumpers no)
		(fp_line
			(start 0.508 -0.9398)
			(end 0.508 0.9398)
			(stroke
				(width 0.1524)
				(type default)
			)
			(layer "B.SilkS")
		)
		(fp_line
			(start -0.508 -0.9398)
			(end 0.508 -0.9398)
			(stroke
				(width 0.1524)
				(type default)
			)
			(layer "B.SilkS")
		)
		(fp_rect
			(start 0.508 0.9398)
			(end -0.508 -0.9398)
			(stroke
				(width 0)
				(type default)
			)
			(fill no)
			(layer "B.CrtYd")
		)
		(fp_rect
			(start 0.508 0.9398)
			(end -0.508 -0.9398)
			(stroke
				(width 0)
				(type default)
			)
			(fill no)
			(layer "B.Fab")
		)
		(pad "1" smd custom
			(at 0 -0.4445 270)
			(size 0.1397 0.1397)
			(layers "B.Cu" "B.Mask" "B.Paste")
			(net "P3V3_STBY")
			(options
				(clearance outline)
				(anchor circle)
			)
			(primitives
				(gr_poly
					(pts
						(arc
							(start -0.1778 0.2794)
							(mid -0.249642 0.249642)
							(end -0.2794 0.1778)
						)
						(arc
							(start -0.2794 -0.1778)
							(mid -0.249642 -0.249642)
							(end -0.1778 -0.2794)
						)
						(arc
							(start 0.1778 -0.2794)
							(mid 0.249642 -0.249642)
							(end 0.2794 -0.1778)
						)
						(arc
							(start 0.2794 0.1778)
							(mid 0.249642 0.249642)
							(end 0.1778 0.2794)
						)
					)
					(width 0)
					(fill yes)
				)
			)
		)
		(pad "2" smd custom
			(at 0 0.4445 270)
			(size 0.1397 0.1397)
			(layers "B.Cu" "B.Mask" "B.Paste")
			(net "ROMD5")
			(options
				(clearance outline)
				(anchor circle)
			)
			(primitives
				(gr_poly
					(pts
						(arc
							(start -0.1778 0.2794)
							(mid -0.249642 0.249642)
							(end -0.2794 0.1778)
						)
						(arc
							(start -0.2794 -0.1778)
							(mid -0.249642 -0.249642)
							(end -0.1778 -0.2794)
						)
						(arc
							(start 0.1778 -0.2794)
							(mid 0.249642 -0.249642)
							(end 0.2794 -0.1778)
						)
						(arc
							(start 0.2794 0.1778)
							(mid 0.249642 0.249642)
							(end 0.1778 0.2794)
						)
					)
					(width 0)
					(fill yes)
				)
			)
		)
	)
	(footprint ""
		(layer "B.Cu")
		(at 198.710296 -87.388192 180)
		(property "Reference" "SC1133"
			(at 0 0 0)
			(layer "B.SilkS")
			(hide yes)
			(effects
				(font
					(size 1.27 1.27)
				)
				(justify mirror)
			)
		)
		(property "Value" "SC1U6D3V1MX-GP"
			(at -1.9177 2.0193 180)
			(unlocked yes)
			(layer "B.Fab")
			(hide yes)
			(effects
				(font
					(size 1.016 1.016)
					(thickness 0.1524)
				)
				(justify mirror)
			)
		)
		(property "Device Type" "C0201H14"
			(at -1.9177 0.4953 180)
			(unlocked yes)
			(layer "B.Fab")
			(hide yes)
			(effects
				(font
					(size 1.016 1.016)
					(thickness 0.1524)
				)
				(justify mirror)
			)
		)
		(duplicate_pad_numbers_are_jumpers no)
		(fp_rect
			(start 0.1524 0.3048)
			(end -0.1524 -0.3048)
			(stroke
				(width 0)
				(type default)
			)
			(fill no)
			(layer "B.CrtYd")
		)
		(fp_poly
			(pts
				(xy 0.2794 0.6477) (xy 0.2794 -0.6477) (xy -0.2794 -0.6477) (xy -0.2794 -0.1905) (xy -0.1524 -0.1905)
				(xy -0.1524 -0.3048) (xy 0.1524 -0.3048) (xy 0.1524 0.3048) (xy -0.1524 0.3048) (xy -0.1524 -0.1778)
				(xy -0.2794 -0.1778) (xy -0.2794 0.6477)
			)
			(stroke
				(width 0)
				(type default)
			)
			(fill no)
			(layer "B.CrtYd")
		)
		(fp_rect
			(start 0.2794 0.6477)
			(end -0.2794 -0.6477)
			(stroke
				(width 0)
				(type default)
			)
			(fill no)
			(layer "B.Fab")
		)
		(pad "1" smd custom
			(at 0 -0.2794)
			(size 0.0762 0.0762)
			(layers "B.Cu" "B.Mask" "B.Paste")
			(net "GB_VDDH2")
			(options
				(clearance outline)
				(anchor circle)
			)
			(primitives
				(gr_poly
					(pts
						(arc
							(start 0.1524 0.127)
							(mid 0.137521 0.162921)
							(end 0.1016 0.1778)
						)
						(arc
							(start -0.1016 0.1778)
							(mid -0.137521 0.162921)
							(end -0.1524 0.127)
						)
						(arc
							(start -0.1524 -0.127)
							(mid -0.137521 -0.162921)
							(end -0.1016 -0.1778)
						)
						(arc
							(start 0.1016 -0.1778)
							(mid 0.137521 -0.162921)
							(end 0.1524 -0.127)
						)
					)
					(width 0)
					(fill yes)
				)
			)
		)
		(pad "2" smd custom
			(at 0 0.2794)
			(size 0.0762 0.0762)
			(layers "B.Cu" "B.Mask" "B.Paste")
			(net "GND")
			(options
				(clearance outline)
				(anchor circle)
			)
			(primitives
				(gr_poly
					(pts
						(arc
							(start 0.1524 0.127)
							(mid 0.137521 0.162921)
							(end 0.1016 0.1778)
						)
						(arc
							(start -0.1016 0.1778)
							(mid -0.137521 0.162921)
							(end -0.1524 0.127)
						)
						(arc
							(start -0.1524 -0.127)
							(mid -0.137521 -0.162921)
							(end -0.1016 -0.1778)
						)
						(arc
							(start 0.1016 -0.1778)
							(mid 0.137521 -0.162921)
							(end 0.1524 -0.127)
						)
					)
					(width 0)
					(fill yes)
				)
			)
		)
	)
)
